# Barreleye-G2_Tri-mode BPX24-DVT-X01-SKU-BOM-X07-20171222_Final.xls.xlsx — TBD AVL Qual (bom)
| NOTES: |  |  |  |  |  |  |
| The following items are alternates to the items listed in the Critical Components Qual tab. |  |  |  |  |  |  |
| These components will be included on near future, non-customer builds for validation and approval by both Customer and the ODM. |  |  |  |  |  |  |
| Item Description | ODM P/N | Customer PN | Vendor | Vendor PN | Build ?? | Estimated Completion Date |
| SATA connectors (black) |  |  |  |  |  |  |
| -  Alternate |  |  |  |  |  |  |
| SATA connectors (blue) |  |  |  |  |  |  |
| -  Alternate |  |  |  |  |  |  |
| PCIe retention |  |  |  |  |  |  |
| -  Alternate |  |  |  |  |  |  |
| RTC XTAL |  |  |  |  |  |  |
| -  Alternate |  |  |  |  |  |  |
| XTAL |  |  |  |  |  |  |
| -  Alternate |  |  |  |  |  |  |
